# SCM (Grand Teton) — schematic netlist excerpt (pin names and nets, part order shuffled) for the footprints in the layout excerpt that follows; sources: Cadence DE-HDL packaged netlist, KiCad conversion of 12092022_DA0F0TMDCD0_F0T_Management_Board_D_brd_V3_OCP.brd

C66  Q_CAP  0.1UF 25V 10% X7R  pkg 0402  page 16 : A = P1V2_AUX ; B = GND
R855  Q_RES  1K 1% CHIP  pkg 0402LF  page 14 : A = FM_BOARD_BMC_REV_ID2 ; B = GND

(kicad_pcb
	(version 20260206)
	(generator "pcbnew")
	(generator_version "10.0")
	(general
		(thickness 1.6)
		(legacy_teardrops no)
	)
	(paper "A4")
	(title_block
		(title "12092022_DA0F0TMDCD0_F0T_Management_Board_D_brd_V3_OCP.brd")
		(comment 1 "Grand Teton / footprints 1027-1028 of 1440")
	)
	(layers
		(0 "F.Cu" signal "TOP")
		(4 "In1.Cu" signal "GND")
		(6 "In2.Cu" signal "IN1")
		(8 "In3.Cu" signal "GND1")
		(10 "In4.Cu" signal "IN2")
		(12 "In5.Cu" signal "VCC")
		(14 "In6.Cu" signal "VCC1")
		(16 "In7.Cu" signal "IN3")
		(18 "In8.Cu" signal "GND2")
		(20 "In9.Cu" signal "IN4")
		(22 "In10.Cu" signal "GND3")
		(2 "B.Cu" signal "BOTTOM")
		(9 "F.Adhes" user "F.Adhesive")
		(11 "B.Adhes" user "B.Adhesive")
		(13 "F.Paste" user "Package Geometry/Pastemask Top")
		(15 "B.Paste" user "Package Geometry/Pastemask Bottom")
		(5 "F.SilkS" user "Ref Des/Silkscreen Top")
		(7 "B.SilkS" user "Ref Des/Silkscreen Bottom")
		(1 "F.Mask" user "Board Geometry/Soldermask Top")
		(3 "B.Mask" user "Board Geometry/Soldermask Bottom")
		(17 "Dwgs.User" user "User.Drawings")
		(19 "Cmts.User" user "User.Comments")
		(21 "Eco1.User" user "User.Eco1")
		(23 "Eco2.User" user "User.Eco2")
		(25 "Edge.Cuts" user "Board Geometry/Outline")
		(27 "Margin" user)
		(31 "F.CrtYd" user "Package Geometry/Place Bound Top")
		(29 "B.CrtYd" user "Package Geometry/Place Bound Bottom")
		(35 "F.Fab" user "Ref Des/Assembly Top")
		(33 "B.Fab" user "Ref Des/Assembly Bottom")
	)
	(footprint ""
		(layer "B.Cu")
		(at 72.39 -19.685 90)
		(property "Reference" "R855"
			(at 0 0 90)
			(layer "B.SilkS")
			(hide yes)
			(effects
				(font
					(size 1.27 1.27)
				)
				(justify mirror)
			)
		)
		(property "Value" ""
			(at 0 0 90)
			(layer "B.Fab")
			(effects
				(font
					(size 1.27 1.27)
				)
				(justify mirror)
			)
		)
		(duplicate_pad_numbers_are_jumpers no)
		(fp_line
			(start 0.7874 -0.4064)
			(end -0.7874 -0.4064)
			(stroke
				(width 0.1524)
				(type default)
			)
			(layer "B.SilkS")
		)
		(fp_line
			(start -0.7874 -0.4064)
			(end -0.7874 0.4064)
			(stroke
				(width 0.1524)
				(type default)
			)
			(layer "B.SilkS")
		)
		(fp_line
			(start 0.7874 0.4064)
			(end 0.7874 -0.4064)
			(stroke
				(width 0.1524)
				(type default)
			)
			(layer "B.SilkS")
		)
		(fp_line
			(start -0.7874 0.4064)
			(end 0.7874 0.4064)
			(stroke
				(width 0.1524)
				(type default)
			)
			(layer "B.SilkS")
		)
		(fp_line
			(start 0.67945 -0.305054)
			(end 0.12065 -0.305054)
			(stroke
				(width 0.1)
				(type default)
			)
			(layer "B.Fab")
		)
		(fp_line
			(start 0.12065 -0.305054)
			(end 0.12065 -0.2794)
			(stroke
				(width 0.1)
				(type default)
			)
			(layer "B.Fab")
		)
		(fp_line
			(start -0.12065 -0.3048)
			(end -0.67945 -0.3048)
			(stroke
				(width 0.1)
				(type default)
			)
			(layer "B.Fab")
		)
		(fp_line
			(start -0.67945 -0.3048)
			(end -0.67945 0.3048)
			(stroke
				(width 0.1)
				(type default)
			)
			(layer "B.Fab")
		)
		(fp_line
			(start 0.12065 -0.2794)
			(end -0.12065 -0.2794)
			(stroke
				(width 0.1)
				(type default)
			)
			(layer "B.Fab")
		)
		(fp_line
			(start -0.12065 -0.2794)
			(end -0.12065 -0.3048)
			(stroke
				(width 0.1)
				(type default)
			)
			(layer "B.Fab")
		)
		(fp_line
			(start 0.12065 0.2794)
			(end 0.12065 0.3048)
			(stroke
				(width 0.1)
				(type default)
			)
			(layer "B.Fab")
		)
		(fp_line
			(start -0.120396 0.2794)
			(end 0.12065 0.2794)
			(stroke
				(width 0.1)
				(type default)
			)
			(layer "B.Fab")
		)
		(fp_line
			(start 0.67945 0.3048)
			(end 0.67945 -0.305054)
			(stroke
				(width 0.1)
				(type default)
			)
			(layer "B.Fab")
		)
		(fp_line
			(start 0.12065 0.3048)
			(end 0.67945 0.3048)
			(stroke
				(width 0.1)
				(type default)
			)
			(layer "B.Fab")
		)
		(fp_line
			(start -0.120396 0.3048)
			(end -0.120396 0.2794)
			(stroke
				(width 0.1)
				(type default)
			)
			(layer "B.Fab")
		)
		(fp_line
			(start -0.67945 0.3048)
			(end -0.120396 0.3048)
			(stroke
				(width 0.1)
				(type default)
			)
			(layer "B.Fab")
		)
		(pad "1" smd circle
			(at 0.40005 0 270)
			(size 0 0)
			(layers "B.Cu" "B.Mask" "B.Paste")
			(net "FM_BOARD_BMC_REV_ID2")
		)
		(pad "2" smd circle
			(at -0.40005 0 270)
			(size 0 0)
			(layers "B.Cu" "B.Mask" "B.Paste")
			(net "GND")
		)
	)
	(footprint ""
		(layer "B.Cu")
		(at 52.494688 -53.564536 -90)
		(property "Reference" "C66"
			(at 0 0 90)
			(layer "B.SilkS")
			(hide yes)
			(effects
				(font
					(size 1.27 1.27)
				)
				(justify mirror)
			)
		)
		(property "Value" ""
			(at 0 0 90)
			(layer "B.Fab")
			(effects
				(font
					(size 1.27 1.27)
				)
				(justify mirror)
			)
		)
		(duplicate_pad_numbers_are_jumpers no)
		(fp_line
			(start -0.7874 0.4064)
			(end 0.7874 0.4064)
			(stroke
				(width 0.1524)
				(type default)
			)
			(layer "B.SilkS")
		)
		(fp_line
			(start 0.7874 0.4064)
			(end 0.7874 -0.4064)
			(stroke
				(width 0.1524)
				(type default)
			)
			(layer "B.SilkS")
		)
		(fp_line
			(start -0.7874 -0.4064)
			(end -0.7874 0.4064)
			(stroke
				(width 0.1524)
				(type default)
			)
			(layer "B.SilkS")
		)
		(fp_line
			(start 0.7874 -0.4064)
			(end -0.7874 -0.4064)
			(stroke
				(width 0.1524)
				(type default)
			)
			(layer "B.SilkS")
		)
		(fp_line
			(start -0.67945 0.3048)
			(end -0.120396 0.3048)
			(stroke
				(width 0.1)
				(type default)
			)
			(layer "B.Fab")
		)
		(fp_line
			(start -0.120396 0.3048)
			(end -0.120396 0.2794)
			(stroke
				(width 0.1)
				(type default)
			)
			(layer "B.Fab")
		)
		(fp_line
			(start 0.12065 0.3048)
			(end 0.67945 0.3048)
			(stroke
				(width 0.1)
				(type default)
			)
			(layer "B.Fab")
		)
		(fp_line
			(start 0.67945 0.3048)
			(end 0.67945 -0.305054)
			(stroke
				(width 0.1)
				(type default)
			)
			(layer "B.Fab")
		)
		(fp_line
			(start -0.120396 0.2794)
			(end 0.12065 0.2794)
			(stroke
				(width 0.1)
				(type default)
			)
			(layer "B.Fab")
		)
		(fp_line
			(start 0.12065 0.2794)
			(end 0.12065 0.3048)
			(stroke
				(width 0.1)
				(type default)
			)
			(layer "B.Fab")
		)
		(fp_line
			(start -0.12065 -0.2794)
			(end -0.12065 -0.3048)
			(stroke
				(width 0.1)
				(type default)
			)
			(layer "B.Fab")
		)
		(fp_line
			(start 0.12065 -0.2794)
			(end -0.12065 -0.2794)
			(stroke
				(width 0.1)
				(type default)
			)
			(layer "B.Fab")
		)
		(fp_line
			(start -0.67945 -0.3048)
			(end -0.67945 0.3048)
			(stroke
				(width 0.1)
				(type default)
			)
			(layer "B.Fab")
		)
		(fp_line
			(start -0.12065 -0.3048)
			(end -0.67945 -0.3048)
			(stroke
				(width 0.1)
				(type default)
			)
			(layer "B.Fab")
		)
		(fp_line
			(start 0.12065 -0.305054)
			(end 0.12065 -0.2794)
			(stroke
				(width 0.1)
				(type default)
			)
			(layer "B.Fab")
		)
		(fp_line
			(start 0.67945 -0.305054)
			(end 0.12065 -0.305054)
			(stroke
				(width 0.1)
				(type default)
			)
			(layer "B.Fab")
		)
		(pad "1" smd circle
			(at 0.40005 0 90)
			(size 0 0)
			(layers "B.Cu" "B.Mask" "B.Paste")
			(net "P1V2_AUX")
		)
		(pad "2" smd circle
			(at -0.40005 0 90)
			(size 0 0)
			(layers "B.Cu" "B.Mask" "B.Paste")
			(net "GND")
		)
	)
)
